# T6G (Grand Teton) — schematic netlist excerpt (pin names and nets, part order shuffled) for the footprints in the layout excerpt that follows; sources: Cadence DE-HDL packaged netlist, KiCad conversion of 04192023_DAF0TMB3IC0_F0TG_MB_C_brd_V02_OCP.brd

R4156  Q_RES  100K 1% CHIP  pkg 0402LF  page 125 : A = P3V3_AUX ; B = PRSNT_CABLE_GPU_A1_ISO_N
PC2159  Q_CAP  1UF 25V 10% X6S  pkg C0402  page 135 : A = P3V3_AUX ; B = GND

(kicad_pcb
	(version 20260206)
	(generator "pcbnew")
	(generator_version "10.0")
	(general
		(thickness 1.6)
		(legacy_teardrops no)
	)
	(paper "A4")
	(title_block
		(title "04192023_DAF0TMB3IC0_F0TG_MB_C_brd_V02_OCP.brd")
		(comment 1 "Grand Teton / footprints 2220-2221 of 8354")
	)
	(layers
		(0 "F.Cu" signal "TOP")
		(4 "In1.Cu" signal "GND")
		(6 "In2.Cu" signal "IN1")
		(8 "In3.Cu" signal "GND1")
		(10 "In4.Cu" signal "IN2")
		(12 "In5.Cu" signal "GND2")
		(14 "In6.Cu" signal "IN3")
		(16 "In7.Cu" signal "GND3")
		(18 "In8.Cu" signal "VCC")
		(20 "In9.Cu" signal "VCC1")
		(22 "In10.Cu" signal "GND4")
		(24 "In11.Cu" signal "IN4")
		(26 "In12.Cu" signal "GND5")
		(28 "In13.Cu" signal "IN5")
		(30 "In14.Cu" signal "GND6")
		(32 "In15.Cu" signal "IN6")
		(34 "In16.Cu" signal "GND7")
		(2 "B.Cu" signal "BOTTOM")
		(9 "F.Adhes" user "F.Adhesive")
		(11 "B.Adhes" user "B.Adhesive")
		(13 "F.Paste" user "Package Geometry/Pastemask Top")
		(15 "B.Paste" user "Package Geometry/Pastemask Bottom")
		(5 "F.SilkS" user "Ref Des/Silkscreen Top")
		(7 "B.SilkS" user "Ref Des/Silkscreen Bottom")
		(1 "F.Mask" user "Board Geometry/Soldermask Top")
		(3 "B.Mask" user "Board Geometry/Soldermask Bottom")
		(17 "Dwgs.User" user "User.Drawings")
		(19 "Cmts.User" user "User.Comments")
		(21 "Eco1.User" user "User.Eco1")
		(23 "Eco2.User" user "User.Eco2")
		(25 "Edge.Cuts" user "Board Geometry/Outline")
		(27 "Margin" user)
		(31 "F.CrtYd" user "Package Geometry/Place Bound Top")
		(29 "B.CrtYd" user "Package Geometry/Place Bound Bottom")
		(35 "F.Fab" user "Ref Des/Assembly Top")
		(33 "B.Fab" user "Ref Des/Assembly Bottom")
	)
	(footprint ""
		(layer "F.Cu")
		(at 418.11194 -105.207308 180)
		(property "Reference" "PC2159"
			(at 0 0 180)
			(layer "F.SilkS")
			(hide yes)
			(effects
				(font
					(size 1.27 1.27)
				)
			)
		)
		(property "Value" ""
			(at 0 0 180)
			(layer "F.Fab")
			(effects
				(font
					(size 1.27 1.27)
				)
			)
		)
		(duplicate_pad_numbers_are_jumpers no)
		(fp_line
			(start 0.7874 0.4064)
			(end -0.7874 0.4064)
			(stroke
				(width 0.1524)
				(type default)
			)
			(layer "F.SilkS")
		)
		(fp_line
			(start 0.7874 -0.4064)
			(end 0.7874 0.4064)
			(stroke
				(width 0.1524)
				(type default)
			)
			(layer "F.SilkS")
		)
		(fp_line
			(start -0.7874 0.4064)
			(end -0.7874 -0.4064)
			(stroke
				(width 0.1524)
				(type default)
			)
			(layer "F.SilkS")
		)
		(fp_line
			(start -0.7874 -0.4064)
			(end 0.7874 -0.4064)
			(stroke
				(width 0.1524)
				(type default)
			)
			(layer "F.SilkS")
		)
		(fp_line
			(start 0.67945 0.3048)
			(end 0.120396 0.3048)
			(stroke
				(width 0.1)
				(type default)
			)
			(layer "F.Fab")
		)
		(fp_line
			(start 0.67945 -0.3048)
			(end 0.67945 0.3048)
			(stroke
				(width 0.1)
				(type default)
			)
			(layer "F.Fab")
		)
		(fp_line
			(start 0.12065 -0.2794)
			(end 0.12065 -0.3048)
			(stroke
				(width 0.1)
				(type default)
			)
			(layer "F.Fab")
		)
		(fp_line
			(start 0.12065 -0.3048)
			(end 0.67945 -0.3048)
			(stroke
				(width 0.1)
				(type default)
			)
			(layer "F.Fab")
		)
		(fp_line
			(start 0.120396 0.3048)
			(end 0.120396 0.2794)
			(stroke
				(width 0.1)
				(type default)
			)
			(layer "F.Fab")
		)
		(fp_line
			(start 0.120396 0.2794)
			(end -0.12065 0.2794)
			(stroke
				(width 0.1)
				(type default)
			)
			(layer "F.Fab")
		)
		(fp_line
			(start -0.12065 0.3048)
			(end -0.67945 0.3048)
			(stroke
				(width 0.1)
				(type default)
			)
			(layer "F.Fab")
		)
		(fp_line
			(start -0.12065 0.2794)
			(end -0.12065 0.3048)
			(stroke
				(width 0.1)
				(type default)
			)
			(layer "F.Fab")
		)
		(fp_line
			(start -0.12065 -0.2794)
			(end 0.12065 -0.2794)
			(stroke
				(width 0.1)
				(type default)
			)
			(layer "F.Fab")
		)
		(fp_line
			(start -0.12065 -0.305054)
			(end -0.12065 -0.2794)
			(stroke
				(width 0.1)
				(type default)
			)
			(layer "F.Fab")
		)
		(fp_line
			(start -0.67945 0.3048)
			(end -0.67945 -0.305054)
			(stroke
				(width 0.1)
				(type default)
			)
			(layer "F.Fab")
		)
		(fp_line
			(start -0.67945 -0.305054)
			(end -0.12065 -0.305054)
			(stroke
				(width 0.1)
				(type default)
			)
			(layer "F.Fab")
		)
		(pad "1" smd circle
			(at -0.40005 0 180)
			(size 0 0)
			(layers "F.Cu" "F.Mask" "F.Paste")
			(net "P3V3_AUX")
		)
		(pad "2" smd circle
			(at 0.40005 0 180)
			(size 0 0)
			(layers "F.Cu" "F.Mask" "F.Paste")
			(net "GND")
		)
	)
	(footprint ""
		(layer "F.Cu")
		(at 357.284782 -413.046418 180)
		(property "Reference" "R4156"
			(at 0 0 180)
			(layer "F.SilkS")
			(hide yes)
			(effects
				(font
					(size 1.27 1.27)
				)
			)
		)
		(property "Value" ""
			(at 0 0 180)
			(layer "F.Fab")
			(effects
				(font
					(size 1.27 1.27)
				)
			)
		)
		(duplicate_pad_numbers_are_jumpers no)
		(fp_line
			(start 0.7874 0.4064)
			(end -0.7874 0.4064)
			(stroke
				(width 0.1524)
				(type default)
			)
			(layer "F.SilkS")
		)
		(fp_line
			(start 0.7874 -0.4064)
			(end 0.7874 0.4064)
			(stroke
				(width 0.1524)
				(type default)
			)
			(layer "F.SilkS")
		)
		(fp_line
			(start -0.7874 0.4064)
			(end -0.7874 -0.4064)
			(stroke
				(width 0.1524)
				(type default)
			)
			(layer "F.SilkS")
		)
		(fp_line
			(start -0.7874 -0.4064)
			(end 0.7874 -0.4064)
			(stroke
				(width 0.1524)
				(type default)
			)
			(layer "F.SilkS")
		)
		(fp_line
			(start 0.67945 0.3048)
			(end 0.120396 0.3048)
			(stroke
				(width 0.1)
				(type default)
			)
			(layer "F.Fab")
		)
		(fp_line
			(start 0.67945 -0.3048)
			(end 0.67945 0.3048)
			(stroke
				(width 0.1)
				(type default)
			)
			(layer "F.Fab")
		)
		(fp_line
			(start 0.12065 -0.2794)
			(end 0.12065 -0.3048)
			(stroke
				(width 0.1)
				(type default)
			)
			(layer "F.Fab")
		)
		(fp_line
			(start 0.12065 -0.3048)
			(end 0.67945 -0.3048)
			(stroke
				(width 0.1)
				(type default)
			)
			(layer "F.Fab")
		)
		(fp_line
			(start 0.120396 0.3048)
			(end 0.120396 0.2794)
			(stroke
				(width 0.1)
				(type default)
			)
			(layer "F.Fab")
		)
		(fp_line
			(start 0.120396 0.2794)
			(end -0.12065 0.2794)
			(stroke
				(width 0.1)
				(type default)
			)
			(layer "F.Fab")
		)
		(fp_line
			(start -0.12065 0.3048)
			(end -0.67945 0.3048)
			(stroke
				(width 0.1)
				(type default)
			)
			(layer "F.Fab")
		)
		(fp_line
			(start -0.12065 0.2794)
			(end -0.12065 0.3048)
			(stroke
				(width 0.1)
				(type default)
			)
			(layer "F.Fab")
		)
		(fp_line
			(start -0.12065 -0.2794)
			(end 0.12065 -0.2794)
			(stroke
				(width 0.1)
				(type default)
			)
			(layer "F.Fab")
		)
		(fp_line
			(start -0.12065 -0.305054)
			(end -0.12065 -0.2794)
			(stroke
				(width 0.1)
				(type default)
			)
			(layer "F.Fab")
		)
		(fp_line
			(start -0.67945 0.3048)
			(end -0.67945 -0.305054)
			(stroke
				(width 0.1)
				(type default)
			)
			(layer "F.Fab")
		)
		(fp_line
			(start -0.67945 -0.305054)
			(end -0.12065 -0.305054)
			(stroke
				(width 0.1)
				(type default)
			)
			(layer "F.Fab")
		)
		(pad "1" smd circle
			(at -0.40005 0 180)
			(size 0 0)
			(layers "F.Cu" "F.Mask" "F.Paste")
			(net "P3V3_AUX")
		)
		(pad "2" smd circle
			(at 0.40005 0 180)
			(size 0 0)
			(layers "F.Cu" "F.Mask" "F.Paste")
			(net "PRSNT_CABLE_GPU_A1_ISO_N")
		)
	)
)
